# S9S_MB_2U (Grand Teton) — schematic netlist excerpt (pin names and nets, part order shuffled) for the footprints in the layout excerpt that follows; sources: Cadence DE-HDL packaged netlist, KiCad conversion of 03242023_DA0F0TMBIJ0_F0T_Motherboard_J_brd_V01_OCP.brd

R2732  Q_RES  33.2 1% CHIP  pkg 0402LF  page 114 : A = PWRGD_CHF_CPU0_DIMM1 ; B = PWRGD_FAIL_CPU0_EF
PR369  Q_RES  1K 1% EMPTY  pkg 0402LF  page 278 : A = PVCCD_HV_CPU0_ISENSE_P ; B = GND

(kicad_pcb
	(version 20260206)
	(generator "pcbnew")
	(generator_version "10.0")
	(general
		(thickness 1.6)
		(legacy_teardrops no)
	)
	(paper "A4")
	(title_block
		(title "03242023_DA0F0TMBIJ0_F0T_Motherboard_J_brd_V01_OCP.brd")
		(comment 1 "Grand Teton / footprints 5994-5995 of 6105")
	)
	(layers
		(0 "F.Cu" signal "TOP")
		(4 "In1.Cu" signal "GND")
		(6 "In2.Cu" signal "IN1")
		(8 "In3.Cu" signal "GND1")
		(10 "In4.Cu" signal "IN2")
		(12 "In5.Cu" signal "GND2")
		(14 "In6.Cu" signal "IN3")
		(16 "In7.Cu" signal "GND3")
		(18 "In8.Cu" signal "VCC")
		(20 "In9.Cu" signal "VCC1")
		(22 "In10.Cu" signal "GND4")
		(24 "In11.Cu" signal "IN4")
		(26 "In12.Cu" signal "GND5")
		(28 "In13.Cu" signal "IN5")
		(30 "In14.Cu" signal "GND6")
		(32 "In15.Cu" signal "IN6")
		(34 "In16.Cu" signal "GND7")
		(2 "B.Cu" signal "BOTTOM")
		(9 "F.Adhes" user "F.Adhesive")
		(11 "B.Adhes" user "B.Adhesive")
		(13 "F.Paste" user "Package Geometry/Pastemask Top")
		(15 "B.Paste" user "Package Geometry/Pastemask Bottom")
		(5 "F.SilkS" user "Ref Des/Silkscreen Top")
		(7 "B.SilkS" user "Ref Des/Silkscreen Bottom")
		(1 "F.Mask" user "Board Geometry/Soldermask Top")
		(3 "B.Mask" user "Board Geometry/Soldermask Bottom")
		(17 "Dwgs.User" user "User.Drawings")
		(19 "Cmts.User" user "User.Comments")
		(21 "Eco1.User" user "User.Eco1")
		(23 "Eco2.User" user "User.Eco2")
		(25 "Edge.Cuts" user "Board Geometry/Outline")
		(27 "Margin" user)
		(31 "F.CrtYd" user "Package Geometry/Place Bound Top")
		(29 "B.CrtYd" user "Package Geometry/Place Bound Bottom")
		(35 "F.Fab" user "Ref Des/Assembly Top")
		(33 "B.Fab" user "Ref Des/Assembly Bottom")
	)
	(footprint ""
		(layer "B.Cu")
		(at 433.073302 -318.868806 90)
		(property "Reference" "R2732"
			(at 0 0 90)
			(layer "B.SilkS")
			(hide yes)
			(effects
				(font
					(size 1.27 1.27)
				)
				(justify mirror)
			)
		)
		(property "Value" ""
			(at 0 0 90)
			(layer "B.Fab")
			(effects
				(font
					(size 1.27 1.27)
				)
				(justify mirror)
			)
		)
		(duplicate_pad_numbers_are_jumpers no)
		(fp_line
			(start 0.7874 -0.4064)
			(end -0.7874 -0.4064)
			(stroke
				(width 0.1524)
				(type default)
			)
			(layer "B.SilkS")
		)
		(fp_line
			(start -0.7874 -0.4064)
			(end -0.7874 0.4064)
			(stroke
				(width 0.1524)
				(type default)
			)
			(layer "B.SilkS")
		)
		(fp_line
			(start 0.7874 0.4064)
			(end 0.7874 -0.4064)
			(stroke
				(width 0.1524)
				(type default)
			)
			(layer "B.SilkS")
		)
		(fp_line
			(start -0.7874 0.4064)
			(end 0.7874 0.4064)
			(stroke
				(width 0.1524)
				(type default)
			)
			(layer "B.SilkS")
		)
		(fp_line
			(start 0.67945 -0.305054)
			(end 0.12065 -0.305054)
			(stroke
				(width 0.1)
				(type default)
			)
			(layer "B.Fab")
		)
		(fp_line
			(start 0.12065 -0.305054)
			(end 0.12065 -0.2794)
			(stroke
				(width 0.1)
				(type default)
			)
			(layer "B.Fab")
		)
		(fp_line
			(start -0.12065 -0.3048)
			(end -0.67945 -0.3048)
			(stroke
				(width 0.1)
				(type default)
			)
			(layer "B.Fab")
		)
		(fp_line
			(start -0.67945 -0.3048)
			(end -0.67945 0.3048)
			(stroke
				(width 0.1)
				(type default)
			)
			(layer "B.Fab")
		)
		(fp_line
			(start 0.12065 -0.2794)
			(end -0.12065 -0.2794)
			(stroke
				(width 0.1)
				(type default)
			)
			(layer "B.Fab")
		)
		(fp_line
			(start -0.12065 -0.2794)
			(end -0.12065 -0.3048)
			(stroke
				(width 0.1)
				(type default)
			)
			(layer "B.Fab")
		)
		(fp_line
			(start 0.12065 0.2794)
			(end 0.12065 0.3048)
			(stroke
				(width 0.1)
				(type default)
			)
			(layer "B.Fab")
		)
		(fp_line
			(start -0.120396 0.2794)
			(end 0.12065 0.2794)
			(stroke
				(width 0.1)
				(type default)
			)
			(layer "B.Fab")
		)
		(fp_line
			(start 0.67945 0.3048)
			(end 0.67945 -0.305054)
			(stroke
				(width 0.1)
				(type default)
			)
			(layer "B.Fab")
		)
		(fp_line
			(start 0.12065 0.3048)
			(end 0.67945 0.3048)
			(stroke
				(width 0.1)
				(type default)
			)
			(layer "B.Fab")
		)
		(fp_line
			(start -0.120396 0.3048)
			(end -0.120396 0.2794)
			(stroke
				(width 0.1)
				(type default)
			)
			(layer "B.Fab")
		)
		(fp_line
			(start -0.67945 0.3048)
			(end -0.120396 0.3048)
			(stroke
				(width 0.1)
				(type default)
			)
			(layer "B.Fab")
		)
		(pad "1" smd circle
			(at 0.40005 0 270)
			(size 0 0)
			(layers "B.Cu" "B.Mask" "B.Paste")
			(net "PWRGD_CHF_CPU0_DIMM1")
		)
		(pad "2" smd circle
			(at -0.40005 0 270)
			(size 0 0)
			(layers "B.Cu" "B.Mask" "B.Paste")
			(net "PWRGD_FAIL_CPU0_EF")
		)
	)
	(footprint ""
		(layer "B.Cu")
		(at 430.77384 -122.281188 180)
		(property "Reference" "PR369"
			(at 0 0 0)
			(layer "B.SilkS")
			(hide yes)
			(effects
				(font
					(size 1.27 1.27)
				)
				(justify mirror)
			)
		)
		(property "Value" ""
			(at 0 0 0)
			(layer "B.Fab")
			(effects
				(font
					(size 1.27 1.27)
				)
				(justify mirror)
			)
		)
		(duplicate_pad_numbers_are_jumpers no)
		(fp_line
			(start 0.7874 0.4064)
			(end 0.7874 -0.4064)
			(stroke
				(width 0.1524)
				(type default)
			)
			(layer "B.SilkS")
		)
		(fp_line
			(start 0.7874 -0.4064)
			(end -0.7874 -0.4064)
			(stroke
				(width 0.1524)
				(type default)
			)
			(layer "B.SilkS")
		)
		(fp_line
			(start -0.7874 0.4064)
			(end 0.7874 0.4064)
			(stroke
				(width 0.1524)
				(type default)
			)
			(layer "B.SilkS")
		)
		(fp_line
			(start -0.7874 -0.4064)
			(end -0.7874 0.4064)
			(stroke
				(width 0.1524)
				(type default)
			)
			(layer "B.SilkS")
		)
		(fp_line
			(start 0.67945 0.3048)
			(end 0.67945 -0.305054)
			(stroke
				(width 0.1)
				(type default)
			)
			(layer "B.Fab")
		)
		(fp_line
			(start 0.67945 -0.305054)
			(end 0.12065 -0.305054)
			(stroke
				(width 0.1)
				(type default)
			)
			(layer "B.Fab")
		)
		(fp_line
			(start 0.12065 0.3048)
			(end 0.67945 0.3048)
			(stroke
				(width 0.1)
				(type default)
			)
			(layer "B.Fab")
		)
		(fp_line
			(start 0.12065 0.2794)
			(end 0.12065 0.3048)
			(stroke
				(width 0.1)
				(type default)
			)
			(layer "B.Fab")
		)
		(fp_line
			(start 0.12065 -0.2794)
			(end -0.12065 -0.2794)
			(stroke
				(width 0.1)
				(type default)
			)
			(layer "B.Fab")
		)
		(fp_line
			(start 0.12065 -0.305054)
			(end 0.12065 -0.2794)
			(stroke
				(width 0.1)
				(type default)
			)
			(layer "B.Fab")
		)
		(fp_line
			(start -0.120396 0.3048)
			(end -0.120396 0.2794)
			(stroke
				(width 0.1)
				(type default)
			)
			(layer "B.Fab")
		)
		(fp_line
			(start -0.120396 0.2794)
			(end 0.12065 0.2794)
			(stroke
				(width 0.1)
				(type default)
			)
			(layer "B.Fab")
		)
		(fp_line
			(start -0.12065 -0.2794)
			(end -0.12065 -0.3048)
			(stroke
				(width 0.1)
				(type default)
			)
			(layer "B.Fab")
		)
		(fp_line
			(start -0.12065 -0.3048)
			(end -0.67945 -0.3048)
			(stroke
				(width 0.1)
				(type default)
			)
			(layer "B.Fab")
		)
		(fp_line
			(start -0.67945 0.3048)
			(end -0.120396 0.3048)
			(stroke
				(width 0.1)
				(type default)
			)
			(layer "B.Fab")
		)
		(fp_line
			(start -0.67945 -0.3048)
			(end -0.67945 0.3048)
			(stroke
				(width 0.1)
				(type default)
			)
			(layer "B.Fab")
		)
		(pad "1" smd circle
			(at 0.40005 0)
			(size 0 0)
			(layers "B.Cu" "B.Mask" "B.Paste")
			(net "PVCCD_HV_CPU0_ISENSE_P")
		)
		(pad "2" smd circle
			(at -0.40005 0)
			(size 0 0)
			(layers "B.Cu" "B.Mask" "B.Paste")
			(net "GND")
		)
	)
)
